(kicad_pcb
	(version 20260206)
	(generator "pcbnew")
	(generator_version "10.0")
	(general
		(thickness 1.6)
		(legacy_teardrops no)
	)
	(paper "A4")
	(title_block
		(title "01162023_DA0F0TEBIF0_F0T_Expander_BD_F_brd_V02_OCP.brd")
		(comment 1 "Grand Teton / footprints 6423-6429 of 9728")
	)
	(layers
		(0 "F.Cu" signal "TOP")
		(4 "In1.Cu" signal "GND")
		(6 "In2.Cu" signal "VCC")
		(8 "In3.Cu" signal "VCC1")
		(10 "In4.Cu" signal "GND1")
		(12 "In5.Cu" signal "IN1")
		(14 "In6.Cu" signal "GND2")
		(16 "In7.Cu" signal "IN2")
		(18 "In8.Cu" signal "GND3")
		(20 "In9.Cu" signal "IN3")
		(22 "In10.Cu" signal "GND4")
		(24 "In11.Cu" signal "IN4")
		(26 "In12.Cu" signal "GND5")
		(28 "In13.Cu" signal "IN5")
		(30 "In14.Cu" signal "GND6")
		(32 "In15.Cu" signal "IN6")
		(34 "In16.Cu" signal "GND7")
		(2 "B.Cu" signal "BOTTOM")
		(9 "F.Adhes" user "F.Adhesive")
		(11 "B.Adhes" user "B.Adhesive")
		(13 "F.Paste" user "Package Geometry/Pastemask Top")
		(15 "B.Paste" user "Package Geometry/Pastemask Bottom")
		(5 "F.SilkS" user "Ref Des/Silkscreen Top")
		(7 "B.SilkS" user "Ref Des/Silkscreen Bottom")
		(1 "F.Mask" user "Board Geometry/Soldermask Top")
		(3 "B.Mask" user "Board Geometry/Soldermask Bottom")
		(17 "Dwgs.User" user "User.Drawings")
		(19 "Cmts.User" user "User.Comments")
		(21 "Eco1.User" user "User.Eco1")
		(23 "Eco2.User" user "User.Eco2")
		(25 "Edge.Cuts" user "Board Geometry/Outline")
		(27 "Margin" user)
		(31 "F.CrtYd" user "Package Geometry/Place Bound Top")
		(29 "B.CrtYd" user "Package Geometry/Place Bound Bottom")
		(35 "F.Fab" user "Ref Des/Assembly Top")
		(33 "B.Fab" user "Ref Des/Assembly Bottom")
	)
	(footprint ""
		(layer "F.Cu")
		(at 112.061244 -37.951156)
		(property "Reference" "Q220"
			(at 0.003556 -1.874774 0)
			(unlocked yes)
			(layer "F.SilkS")
			(effects
				(font
					(size 0.7874 0.5842)
					(thickness 0.1524)
				)
			)
		)
		(property "Value" ""
			(at 0 0 0)
			(layer "F.Fab")
			(effects
				(font
					(size 1.27 1.27)
				)
			)
		)
		(duplicate_pad_numbers_are_jumpers no)
		(fp_line
			(start -1.376172 -1.199896)
			(end -0.508 -1.199896)
			(stroke
				(width 0.1524)
				(type default)
			)
			(layer "F.SilkS")
		)
		(fp_line
			(start -1.376172 1.199896)
			(end -1.376172 -1.199896)
			(stroke
				(width 0.1524)
				(type default)
			)
			(layer "F.SilkS")
		)
		(fp_line
			(start -0.508 -1.199896)
			(end 0 -0.762)
			(stroke
				(width 0.1524)
				(type default)
			)
			(layer "F.SilkS")
		)
		(fp_line
			(start 0 -0.762)
			(end 0.508 -1.199896)
			(stroke
				(width 0.1524)
				(type default)
			)
			(layer "F.SilkS")
		)
		(fp_line
			(start 0.508 -1.199896)
			(end 1.376172 -1.199896)
			(stroke
				(width 0.1524)
				(type default)
			)
			(layer "F.SilkS")
		)
		(fp_line
			(start 1.376172 -1.199896)
			(end 1.376172 1.199896)
			(stroke
				(width 0.1524)
				(type default)
			)
			(layer "F.SilkS")
		)
		(fp_line
			(start 1.376172 1.199896)
			(end -1.376172 1.199896)
			(stroke
				(width 0.1524)
				(type default)
			)
			(layer "F.SilkS")
		)
		(fp_poly
			(pts
				(xy -1.63576 -1.119378) (xy -1.905254 -1.927606) (xy -2.443988 -1.388872)
			)
			(stroke
				(width 0)
				(type default)
			)
			(fill yes)
			(layer "F.SilkS")
		)
		(fp_line
			(start -0.674878 -1.100074)
			(end 0.674878 -1.100074)
			(stroke
				(width 0.1)
				(type default)
			)
			(layer "F.Fab")
		)
		(fp_line
			(start -0.674878 1.100074)
			(end -0.674878 -1.100074)
			(stroke
				(width 0.1)
				(type default)
			)
			(layer "F.Fab")
		)
		(fp_line
			(start 0.674878 -1.100074)
			(end 0.674878 1.100074)
			(stroke
				(width 0.1)
				(type default)
			)
			(layer "F.Fab")
		)
		(fp_line
			(start 0.674878 1.100074)
			(end -0.674878 1.100074)
			(stroke
				(width 0.1)
				(type default)
			)
			(layer "F.Fab")
		)
		(fp_poly
			(pts
				(xy -1.4605 -0.7493) (xy -2.2225 -1.1303) (xy -2.2225 -0.3683)
			)
			(stroke
				(width 0)
				(type default)
			)
			(fill yes)
			(layer "F.Fab")
		)
		(pad "1" smd rect
			(at -0.899922 -0.750062 270)
			(size 0.6096 0.6096)
			(layers "F.Cu" "F.Mask" "F.Paste")
			(net "GND")
		)
		(pad "2" smd rect
			(at -0.899922 0 270)
			(size 0.4064 0.6096)
			(layers "F.Cu" "F.Mask" "F.Paste")
			(net "P3V3_SSD4_PG_G1")
		)
		(pad "3" smd rect
			(at -0.899922 0.750062 270)
			(size 0.6096 0.6096)
			(layers "F.Cu" "F.Mask" "F.Paste")
			(net "PWRGD_P3V3_SSD4_D")
		)
		(pad "4" smd rect
			(at 0.899922 0.750062 270)
			(size 0.6096 0.6096)
			(layers "F.Cu" "F.Mask" "F.Paste")
			(net "GND")
		)
		(pad "5" smd rect
			(at 0.899922 0 270)
			(size 0.4064 0.6096)
			(layers "F.Cu" "F.Mask" "F.Paste")
			(net "P3V3_SSD4_PG_G2")
		)
		(pad "6" smd rect
			(at 0.899922 -0.750062 270)
			(size 0.6096 0.6096)
			(layers "F.Cu" "F.Mask" "F.Paste")
			(net "P3V3_SSD4_PG_G2")
		)
	)
	(footprint ""
		(layer "F.Cu")
		(at 5.999988 -407.599896)
		(property "Reference" "H53"
			(at -3.804412 -5.609336 0)
			(unlocked yes)
			(layer "F.SilkS")
			(effects
				(font
					(size 0.7874 0.5842)
					(thickness 0.1524)
				)
				(justify left)
			)
		)
		(property "Value" ""
			(at 0 0 0)
			(layer "F.Fab")
			(effects
				(font
					(size 1.27 1.27)
				)
			)
		)
		(duplicate_pad_numbers_are_jumpers no)
		(pad "1" thru_hole circle
			(at 0 0)
			(size 10.0076 10.0076)
			(drill 5.6134)
			(layers "*.Cu" "*.Mask")
			(remove_unused_layers no)
			(net "GND")
			(clearance -1.9431)
		)
	)
	(footprint ""
		(layer "F.Cu")
		(at 74.027792 -35.876738)
		(property "Reference" "R5883"
			(at 0 0 0)
			(layer "F.SilkS")
			(hide yes)
			(effects
				(font
					(size 1.27 1.27)
				)
			)
		)
		(property "Value" ""
			(at 0 0 0)
			(layer "F.Fab")
			(effects
				(font
					(size 1.27 1.27)
				)
			)
		)
		(duplicate_pad_numbers_are_jumpers no)
		(fp_line
			(start -0.7874 -0.4064)
			(end 0.7874 -0.4064)
			(stroke
				(width 0.1524)
				(type default)
			)
			(layer "F.SilkS")
		)
		(fp_line
			(start -0.7874 0.4064)
			(end -0.7874 -0.4064)
			(stroke
				(width 0.1524)
				(type default)
			)
			(layer "F.SilkS")
		)
		(fp_line
			(start 0.7874 -0.4064)
			(end 0.7874 0.4064)
			(stroke
				(width 0.1524)
				(type default)
			)
			(layer "F.SilkS")
		)
		(fp_line
			(start 0.7874 0.4064)
			(end -0.7874 0.4064)
			(stroke
				(width 0.1524)
				(type default)
			)
			(layer "F.SilkS")
		)
		(fp_line
			(start -0.67945 -0.305054)
			(end -0.12065 -0.305054)
			(stroke
				(width 0.1)
				(type default)
			)
			(layer "F.Fab")
		)
		(fp_line
			(start -0.67945 0.3048)
			(end -0.67945 -0.305054)
			(stroke
				(width 0.1)
				(type default)
			)
			(layer "F.Fab")
		)
		(fp_line
			(start -0.12065 -0.305054)
			(end -0.12065 -0.2794)
			(stroke
				(width 0.1)
				(type default)
			)
			(layer "F.Fab")
		)
		(fp_line
			(start -0.12065 -0.2794)
			(end 0.12065 -0.2794)
			(stroke
				(width 0.1)
				(type default)
			)
			(layer "F.Fab")
		)
		(fp_line
			(start -0.12065 0.2794)
			(end -0.12065 0.3048)
			(stroke
				(width 0.1)
				(type default)
			)
			(layer "F.Fab")
		)
		(fp_line
			(start -0.12065 0.3048)
			(end -0.67945 0.3048)
			(stroke
				(width 0.1)
				(type default)
			)
			(layer "F.Fab")
		)
		(fp_line
			(start 0.120396 0.2794)
			(end -0.12065 0.2794)
			(stroke
				(width 0.1)
				(type default)
			)
			(layer "F.Fab")
		)
		(fp_line
			(start 0.120396 0.3048)
			(end 0.120396 0.2794)
			(stroke
				(width 0.1)
				(type default)
			)
			(layer "F.Fab")
		)
		(fp_line
			(start 0.12065 -0.3048)
			(end 0.67945 -0.3048)
			(stroke
				(width 0.1)
				(type default)
			)
			(layer "F.Fab")
		)
		(fp_line
			(start 0.12065 -0.2794)
			(end 0.12065 -0.3048)
			(stroke
				(width 0.1)
				(type default)
			)
			(layer "F.Fab")
		)
		(fp_line
			(start 0.67945 -0.3048)
			(end 0.67945 0.3048)
			(stroke
				(width 0.1)
				(type default)
			)
			(layer "F.Fab")
		)
		(fp_line
			(start 0.67945 0.3048)
			(end 0.120396 0.3048)
			(stroke
				(width 0.1)
				(type default)
			)
			(layer "F.Fab")
		)
		(pad "1" smd circle
			(at -0.40005 0)
			(size 0 0)
			(layers "F.Cu" "F.Mask" "F.Paste")
			(net "PWRGD_P3V3_SSD3_D")
		)
		(pad "2" smd circle
			(at 0.40005 0)
			(size 0 0)
			(layers "F.Cu" "F.Mask" "F.Paste")
			(net "PWRGD_P3V3_SSD3_R")
		)
	)
	(footprint ""
		(layer "F.Cu")
		(at 52.267866 -52.035456 180)
		(property "Reference" "R863"
			(at 0 0 180)
			(layer "F.SilkS")
			(hide yes)
			(effects
				(font
					(size 1.27 1.27)
				)
			)
		)
		(property "Value" ""
			(at 0 0 180)
			(layer "F.Fab")
			(effects
				(font
					(size 1.27 1.27)
				)
			)
		)
		(duplicate_pad_numbers_are_jumpers no)
		(fp_line
			(start 0.7874 0.4064)
			(end -0.7874 0.4064)
			(stroke
				(width 0.1524)
				(type default)
			)
			(layer "F.SilkS")
		)
		(fp_line
			(start 0.7874 -0.4064)
			(end 0.7874 0.4064)
			(stroke
				(width 0.1524)
				(type default)
			)
			(layer "F.SilkS")
		)
		(fp_line
			(start -0.7874 0.4064)
			(end -0.7874 -0.4064)
			(stroke
				(width 0.1524)
				(type default)
			)
			(layer "F.SilkS")
		)
		(fp_line
			(start -0.7874 -0.4064)
			(end 0.7874 -0.4064)
			(stroke
				(width 0.1524)
				(type default)
			)
			(layer "F.SilkS")
		)
		(fp_line
			(start 0.67945 0.3048)
			(end 0.120396 0.3048)
			(stroke
				(width 0.1)
				(type default)
			)
			(layer "F.Fab")
		)
		(fp_line
			(start 0.67945 -0.3048)
			(end 0.67945 0.3048)
			(stroke
				(width 0.1)
				(type default)
			)
			(layer "F.Fab")
		)
		(fp_line
			(start 0.12065 -0.2794)
			(end 0.12065 -0.3048)
			(stroke
				(width 0.1)
				(type default)
			)
			(layer "F.Fab")
		)
		(fp_line
			(start 0.12065 -0.3048)
			(end 0.67945 -0.3048)
			(stroke
				(width 0.1)
				(type default)
			)
			(layer "F.Fab")
		)
		(fp_line
			(start 0.120396 0.3048)
			(end 0.120396 0.2794)
			(stroke
				(width 0.1)
				(type default)
			)
			(layer "F.Fab")
		)
		(fp_line
			(start 0.120396 0.2794)
			(end -0.12065 0.2794)
			(stroke
				(width 0.1)
				(type default)
			)
			(layer "F.Fab")
		)
		(fp_line
			(start -0.12065 0.3048)
			(end -0.67945 0.3048)
			(stroke
				(width 0.1)
				(type default)
			)
			(layer "F.Fab")
		)
		(fp_line
			(start -0.12065 0.2794)
			(end -0.12065 0.3048)
			(stroke
				(width 0.1)
				(type default)
			)
			(layer "F.Fab")
		)
		(fp_line
			(start -0.12065 -0.2794)
			(end 0.12065 -0.2794)
			(stroke
				(width 0.1)
				(type default)
			)
			(layer "F.Fab")
		)
		(fp_line
			(start -0.12065 -0.305054)
			(end -0.12065 -0.2794)
			(stroke
				(width 0.1)
				(type default)
			)
			(layer "F.Fab")
		)
		(fp_line
			(start -0.67945 0.3048)
			(end -0.67945 -0.305054)
			(stroke
				(width 0.1)
				(type default)
			)
			(layer "F.Fab")
		)
		(fp_line
			(start -0.67945 -0.305054)
			(end -0.12065 -0.305054)
			(stroke
				(width 0.1)
				(type default)
			)
			(layer "F.Fab")
		)
		(pad "1" smd circle
			(at -0.40005 0 180)
			(size 0 0)
			(layers "F.Cu" "F.Mask" "F.Paste")
			(net "P3V3_AUX")
		)
		(pad "2" smd circle
			(at 0.40005 0 180)
			(size 0 0)
			(layers "F.Cu" "F.Mask" "F.Paste")
			(net "PWRGD_P12V_SSD1")
		)
	)
	(footprint ""
		(layer "F.Cu")
		(at 59.007756 -229.6668)
		(property "Reference" "J72"
			(at -1.458976 -4.433824 0)
			(unlocked yes)
			(layer "F.SilkS")
			(effects
				(font
					(size 0.7874 0.5842)
					(thickness 0.1524)
				)
				(justify left)
			)
		)
		(property "Value" ""
			(at 0 0 0)
			(layer "F.Fab")
			(effects
				(font
					(size 1.27 1.27)
				)
			)
		)
		(duplicate_pad_numbers_are_jumpers no)
		(fp_line
			(start -1.27 -3.81)
			(end 1.27 -3.81)
			(stroke
				(width 0.1524)
				(type default)
			)
			(layer "F.SilkS")
		)
		(fp_line
			(start -1.27 -0.7747)
			(end -1.27 -3.81)
			(stroke
				(width 0.1524)
				(type default)
			)
			(layer "F.SilkS")
		)
		(fp_line
			(start -1.27 3.81)
			(end -1.27 0.7747)
			(stroke
				(width 0.1524)
				(type default)
			)
			(layer "F.SilkS")
		)
		(fp_line
			(start 1.27 -3.81)
			(end 1.27 -3.3147)
			(stroke
				(width 0.1524)
				(type default)
			)
			(layer "F.SilkS")
		)
		(fp_line
			(start 1.27 -1.7653)
			(end 1.27 1.7653)
			(stroke
				(width 0.1524)
				(type default)
			)
			(layer "F.SilkS")
		)
		(fp_line
			(start 1.27 3.3147)
			(end 1.27 3.81)
			(stroke
				(width 0.1524)
				(type default)
			)
			(layer "F.SilkS")
		)
		(fp_line
			(start 1.27 3.81)
			(end -1.27 3.81)
			(stroke
				(width 0.1524)
				(type default)
			)
			(layer "F.SilkS")
		)
		(fp_poly
			(pts
				(xy 4.3942 -3.048) (xy 4.3942 -2.032) (xy 3.3782 -2.54)
			)
			(stroke
				(width 0)
				(type default)
			)
			(fill yes)
			(layer "F.SilkS")
		)
		(fp_line
			(start -1.27 -3.81)
			(end -1.27 3.81)
			(stroke
				(width 0.1)
				(type default)
			)
			(layer "F.Fab")
		)
		(fp_line
			(start -1.27 3.81)
			(end 1.27 3.81)
			(stroke
				(width 0.1)
				(type default)
			)
			(layer "F.Fab")
		)
		(fp_line
			(start 1.27 -3.81)
			(end -1.27 -3.81)
			(stroke
				(width 0.1)
				(type default)
			)
			(layer "F.Fab")
		)
		(fp_line
			(start 1.27 3.81)
			(end 1.27 -3.81)
			(stroke
				(width 0.1)
				(type default)
			)
			(layer "F.Fab")
		)
		(fp_poly
			(pts
				(xy 4.3942 -3.048) (xy 4.3942 -2.032) (xy 3.3782 -2.54)
			)
			(stroke
				(width 0)
				(type default)
			)
			(fill yes)
			(layer "F.Fab")
		)
		(fp_text user "3"
			(at 3.921252 2.54 90)
			(unlocked yes)
			(layer "F.SilkS")
			(effects
				(font
					(size 0.7874 0.5842)
					(thickness 0.1524)
				)
			)
		)
		(fp_text user "3"
			(at 3.921252 2.54 90)
			(unlocked yes)
			(layer "F.Fab")
			(effects
				(font
					(size 0.7874 0.5842)
					(thickness 0.1524)
				)
			)
		)
		(pad "1" smd rect
			(at 1.459992 -2.54 90)
			(size 1.27 3.429)
			(layers "F.Cu" "F.Mask" "F.Paste")
			(net "GND")
		)
		(pad "2" smd rect
			(at -1.459992 0 90)
			(size 1.27 3.429)
			(layers "F.Cu" "F.Mask" "F.Paste")
			(net "UART_PEX1_CLI_BUF_R1_TX")
		)
		(pad "3" smd rect
			(at 1.459992 2.54 90)
			(size 1.27 3.429)
			(layers "F.Cu" "F.Mask" "F.Paste")
			(net "UART_PEX1_CLI_R1_RX")
		)
	)
	(footprint ""
		(layer "F.Cu")
		(at 188.37402 -72.766682 90)
		(property "Reference" "PR7070"
			(at 0 0 90)
			(layer "F.SilkS")
			(hide yes)
			(effects
				(font
					(size 1.27 1.27)
				)
			)
		)
		(property "Value" ""
			(at 0 0 90)
			(layer "F.Fab")
			(effects
				(font
					(size 1.27 1.27)
				)
			)
		)
		(duplicate_pad_numbers_are_jumpers no)
		(fp_line
			(start 0.7874 -0.4064)
			(end 0.7874 0.4064)
			(stroke
				(width 0.1524)
				(type default)
			)
			(layer "F.SilkS")
		)
		(fp_line
			(start -0.7874 -0.4064)
			(end 0.7874 -0.4064)
			(stroke
				(width 0.1524)
				(type default)
			)
			(layer "F.SilkS")
		)
		(fp_line
			(start 0.7874 0.4064)
			(end -0.7874 0.4064)
			(stroke
				(width 0.1524)
				(type default)
			)
			(layer "F.SilkS")
		)
		(fp_line
			(start -0.7874 0.4064)
			(end -0.7874 -0.4064)
			(stroke
				(width 0.1524)
				(type default)
			)
			(layer "F.SilkS")
		)
		(fp_line
			(start -0.12065 -0.305054)
			(end -0.12065 -0.2794)
			(stroke
				(width 0.1)
				(type default)
			)
			(layer "F.Fab")
		)
		(fp_line
			(start -0.67945 -0.305054)
			(end -0.12065 -0.305054)
			(stroke
				(width 0.1)
				(type default)
			)
			(layer "F.Fab")
		)
		(fp_line
			(start 0.67945 -0.3048)
			(end 0.67945 0.3048)
			(stroke
				(width 0.1)
				(type default)
			)
			(layer "F.Fab")
		)
		(fp_line
			(start 0.12065 -0.3048)
			(end 0.67945 -0.3048)
			(stroke
				(width 0.1)
				(type default)
			)
			(layer "F.Fab")
		)
		(fp_line
			(start 0.12065 -0.2794)
			(end 0.12065 -0.3048)
			(stroke
				(width 0.1)
				(type default)
			)
			(layer "F.Fab")
		)
		(fp_line
			(start -0.12065 -0.2794)
			(end 0.12065 -0.2794)
			(stroke
				(width 0.1)
				(type default)
			)
			(layer "F.Fab")
		)
		(fp_line
			(start 0.120396 0.2794)
			(end -0.12065 0.2794)
			(stroke
				(width 0.1)
				(type default)
			)
			(layer "F.Fab")
		)
		(fp_line
			(start -0.12065 0.2794)
			(end -0.12065 0.3048)
			(stroke
				(width 0.1)
				(type default)
			)
			(layer "F.Fab")
		)
		(fp_line
			(start 0.67945 0.3048)
			(end 0.120396 0.3048)
			(stroke
				(width 0.1)
				(type default)
			)
			(layer "F.Fab")
		)
		(fp_line
			(start 0.120396 0.3048)
			(end 0.120396 0.2794)
			(stroke
				(width 0.1)
				(type default)
			)
			(layer "F.Fab")
		)
		(fp_line
			(start -0.12065 0.3048)
			(end -0.67945 0.3048)
			(stroke
				(width 0.1)
				(type default)
			)
			(layer "F.Fab")
		)
		(fp_line
			(start -0.67945 0.3048)
			(end -0.67945 -0.305054)
			(stroke
				(width 0.1)
				(type default)
			)
			(layer "F.Fab")
		)
		(pad "1" smd circle
			(at -0.40005 0 90)
			(size 0 0)
			(layers "F.Cu" "F.Mask" "F.Paste")
			(net "P12V_SSD6_CO_MODE")
		)
		(pad "2" smd circle
			(at 0.40005 0 90)
			(size 0 0)
			(layers "F.Cu" "F.Mask" "F.Paste")
			(net "GND")
		)
	)
	(footprint ""
		(layer "F.Cu")
		(at 259.662422 -22.937216 90)
		(property "Reference" "R1697"
			(at 0 0 90)
			(layer "F.SilkS")
			(hide yes)
			(effects
				(font
					(size 1.27 1.27)
				)
			)
		)
		(property "Value" ""
			(at 0 0 90)
			(layer "F.Fab")
			(effects
				(font
					(size 1.27 1.27)
				)
			)
		)
		(duplicate_pad_numbers_are_jumpers no)
		(fp_line
			(start 0.7874 -0.4064)
			(end 0.7874 0.4064)
			(stroke
				(width 0.1524)
				(type default)
			)
			(layer "F.SilkS")
		)
		(fp_line
			(start -0.7874 -0.4064)
			(end 0.7874 -0.4064)
			(stroke
				(width 0.1524)
				(type default)
			)
			(layer "F.SilkS")
		)
		(fp_line
			(start 0.7874 0.4064)
			(end -0.7874 0.4064)
			(stroke
				(width 0.1524)
				(type default)
			)
			(layer "F.SilkS")
		)
		(fp_line
			(start -0.7874 0.4064)
			(end -0.7874 -0.4064)
			(stroke
				(width 0.1524)
				(type default)
			)
			(layer "F.SilkS")
		)
		(fp_line
			(start -0.12065 -0.305054)
			(end -0.12065 -0.2794)
			(stroke
				(width 0.1)
				(type default)
			)
			(layer "F.Fab")
		)
		(fp_line
			(start -0.67945 -0.305054)
			(end -0.12065 -0.305054)
			(stroke
				(width 0.1)
				(type default)
			)
			(layer "F.Fab")
		)
		(fp_line
			(start 0.67945 -0.3048)
			(end 0.67945 0.3048)
			(stroke
				(width 0.1)
				(type default)
			)
			(layer "F.Fab")
		)
		(fp_line
			(start 0.12065 -0.3048)
			(end 0.67945 -0.3048)
			(stroke
				(width 0.1)
				(type default)
			)
			(layer "F.Fab")
		)
		(fp_line
			(start 0.12065 -0.2794)
			(end 0.12065 -0.3048)
			(stroke
				(width 0.1)
				(type default)
			)
			(layer "F.Fab")
		)
		(fp_line
			(start -0.12065 -0.2794)
			(end 0.12065 -0.2794)
			(stroke
				(width 0.1)
				(type default)
			)
			(layer "F.Fab")
		)
		(fp_line
			(start 0.120396 0.2794)
			(end -0.12065 0.2794)
			(stroke
				(width 0.1)
				(type default)
			)
			(layer "F.Fab")
		)
		(fp_line
			(start -0.12065 0.2794)
			(end -0.12065 0.3048)
			(stroke
				(width 0.1)
				(type default)
			)
			(layer "F.Fab")
		)
		(fp_line
			(start 0.67945 0.3048)
			(end 0.120396 0.3048)
			(stroke
				(width 0.1)
				(type default)
			)
			(layer "F.Fab")
		)
		(fp_line
			(start 0.120396 0.3048)
			(end 0.120396 0.2794)
			(stroke
				(width 0.1)
				(type default)
			)
			(layer "F.Fab")
		)
		(fp_line
			(start -0.12065 0.3048)
			(end -0.67945 0.3048)
			(stroke
				(width 0.1)
				(type default)
			)
			(layer "F.Fab")
		)
		(fp_line
			(start -0.67945 0.3048)
			(end -0.67945 -0.305054)
			(stroke
				(width 0.1)
				(type default)
			)
			(layer "F.Fab")
		)
		(pad "1" smd circle
			(at -0.40005 0 90)
			(size 0 0)
			(layers "F.Cu" "F.Mask" "F.Paste")
			(net "SMB_BIC_I2C9_MUX1_SSD8_R_SDA")
		)
		(pad "2" smd circle
			(at 0.40005 0 90)
			(size 0 0)
			(layers "F.Cu" "F.Mask" "F.Paste")
			(net "SMB_ISO_SSD8_SDA")
		)
	)
)
